(kicad_pcb
	(version 20241229)
	(generator "pcbnew")
	(generator_version "9.0")
	(general
		(thickness 1.61)
		(legacy_teardrops no)
	)
	(paper "A3")
	(title_block
		(title "RDIMM DDR5 Tester")
		(date "2026-05-21")
		(rev "2.2.0")
		(company "Antmicro")
		(comment 9 "footprints 349-351 of 796")
	)
	(layers
		(0 "F.Cu" signal)
		(4 "In1.Cu" power)
		(6 "In2.Cu" mixed)
		(8 "In3.Cu" power)
		(10 "In4.Cu" mixed)
		(12 "In5.Cu" power)
		(14 "In6.Cu" mixed)
		(16 "In7.Cu" power)
		(18 "In8.Cu" power)
		(20 "In9.Cu" mixed)
		(22 "In10.Cu" power)
		(2 "B.Cu" signal)
		(9 "F.Adhes" user "F.Adhesive")
		(11 "B.Adhes" user "B.Adhesive")
		(13 "F.Paste" user)
		(15 "B.Paste" user)
		(5 "F.SilkS" user "F.Silkscreen")
		(7 "B.SilkS" user "B.Silkscreen")
		(1 "F.Mask" user)
		(3 "B.Mask" user)
		(17 "Dwgs.User" user "User.Drawings")
		(19 "Cmts.User" user "User.Comments")
		(21 "Eco1.User" user "User.Eco1")
		(23 "Eco2.User" user "User.Eco2")
		(25 "Edge.Cuts" user)
		(27 "Margin" user)
		(31 "F.CrtYd" user "F.Courtyard")
		(29 "B.CrtYd" user "B.Courtyard")
		(35 "F.Fab" user)
		(33 "B.Fab" user)
	)
	(footprint "antmicro-footprints:SOT1161-2"
		(layer "F.Cu")
		(at 119.823 159.398 180)
		(descr "SOT1161-2")
		(tags "Integrated Circuit")
		(property "Reference" "U40"
			(at 0.273 -2.752 0)
			(layer "F.SilkS")
			(effects
				(font
					(size 0.7 0.7)
					(thickness 0.15)
				)
				(justify right bottom)
			)
		)
		(property "Value" "NVT4858_XQFN"
			(at 0 2.7 0)
			(layer "F.Fab")
			(effects
				(font
					(size 0.7 0.7)
					(thickness 0.15)
				)
				(justify right bottom)
			)
		)
		(property "Datasheet" "https://www.nxp.com/docs/en/data-sheet/NVT4858DS.pdf"
			(at 0 0 180)
			(layer "F.Fab")
			(hide yes)
			(effects
				(font
					(size 1.27 1.27)
					(thickness 0.15)
				)
			)
		)
		(property "Manufacturer" "NXP"
			(at 0 0 180)
			(unlocked yes)
			(layer "F.Fab")
			(hide yes)
			(effects
				(font
					(size 1 1)
					(thickness 0.15)
				)
			)
		)
		(property "MPN" "NVT4858HKZ"
			(at 0 0 180)
			(unlocked yes)
			(layer "F.Fab")
			(hide yes)
			(effects
				(font
					(size 1 1)
					(thickness 0.15)
				)
			)
		)
		(property "Author" "Antmicro"
			(at 0 0 180)
			(unlocked yes)
			(layer "F.Fab")
			(hide yes)
			(effects
				(font
					(size 1 1)
					(thickness 0.15)
				)
			)
		)
		(property "License" "Apache-2.0"
			(at 0 0 180)
			(unlocked yes)
			(layer "F.Fab")
			(hide yes)
			(effects
				(font
					(size 1 1)
					(thickness 0.15)
				)
			)
		)
		(sheetname "/HDMI + SD Card/")
		(sheetfile "hdmi-sd-card.kicad_sch")
		(attr smd)
		(fp_line
			(start 0.9 0.9)
			(end 0.9 1.3)
			(stroke
				(width 0.15)
				(type solid)
			)
			(layer "F.SilkS")
		)
		(fp_line
			(start 0.9 -0.901)
			(end 0.9 -1.301)
			(stroke
				(width 0.15)
				(type solid)
			)
			(layer "F.SilkS")
		)
		(fp_line
			(start -0.9 -0.9)
			(end -0.9 -1.3)
			(stroke
				(width 0.15)
				(type solid)
			)
			(layer "F.SilkS")
		)
		(fp_line
			(start -0.902 0.9)
			(end -0.902 1.3)
			(stroke
				(width 0.15)
				(type solid)
			)
			(layer "F.SilkS")
		)
		(fp_circle
			(center -1.6 -1.7)
			(end -1.55 -1.7)
			(stroke
				(width 0.15)
				(type solid)
			)
			(fill yes)
			(layer "F.SilkS")
		)
		(fp_rect
			(start -1.3 -1.7)
			(end 1.3 1.7)
			(stroke
				(width 0.05)
				(type solid)
			)
			(fill no)
			(layer "F.CrtYd")
		)
		(fp_line
			(start 0.9 1.3)
			(end -0.902 1.3)
			(stroke
				(width 0.15)
				(type solid)
			)
			(layer "F.Fab")
		)
		(fp_line
			(start 0.9 -1.301)
			(end 0.9 1.3)
			(stroke
				(width 0.15)
				(type solid)
			)
			(layer "F.Fab")
		)
		(fp_line
			(start -0.902 1.3)
			(end -0.902 -1.301)
			(stroke
				(width 0.15)
				(type solid)
			)
			(layer "F.Fab")
		)
		(fp_line
			(start -0.902 -1.301)
			(end 0.9 -1.301)
			(stroke
				(width 0.15)
				(type solid)
			)
			(layer "F.Fab")
		)
		(fp_text user "Author: Antmicro"
			(at -1.5 4.498 180)
			(layer "F.Fab")
			(effects
				(font
					(size 0.7 0.7)
					(thickness 0.15)
				)
				(justify left bottom)
			)
		)
		(fp_text user "License: Apache-2.0"
			(at -1.5 5.7 180)
			(layer "F.Fab")
			(effects
				(font
					(size 0.7 0.7)
					(thickness 0.15)
				)
				(justify left bottom)
			)
		)
		(pad "1" smd roundrect
			(at -0.6 -0.6 270)
			(size 0.22 0.9)
			(layers "F.Cu" "F.Mask" "F.Paste")
			(roundrect_rratio 0.25)
			(net 640 "/FPGA banks HP/SD.DAT2")
			(pinfunction "DAT2_{A}")
			(pintype "bidirectional")
		)
		(pad "2" smd roundrect
			(at -0.625 -0.202 270)
			(size 0.22 0.9)
			(layers "F.Cu" "F.Mask" "F.Paste")
			(roundrect_rratio 0.25)
			(net 641 "/FPGA banks HP/SD.DAT3")
			(pinfunction "DAT3_{A}")
			(pintype "bidirectional")
		)
		(pad "3" smd roundrect
			(at -0.625 0.2 270)
			(size 0.22 0.9)
			(layers "F.Cu" "F.Mask" "F.Paste")
			(roundrect_rratio 0.25)
			(net 638 "/FPGA banks HP/SD.DAT0")
			(pinfunction "DAT0_{A}")
			(pintype "bidirectional")
		)
		(pad "4" smd roundrect
			(at -0.625 0.598 270)
			(size 0.22 0.9)
			(layers "F.Cu" "F.Mask" "F.Paste")
			(roundrect_rratio 0.25)
			(net 639 "/FPGA banks HP/SD.DAT1")
			(pinfunction "DAT1_{A}")
			(pintype "bidirectional")
		)
		(pad "5" smd roundrect
			(at -0.6 1.175 180)
			(size 0.22 0.55)
			(layers "F.Cu" "F.Mask" "F.Paste")
			(roundrect_rratio 0.25)
			(net 636 "/FPGA banks HP/SD.CLK")
			(pinfunction "CLK_{A}")
			(pintype "input")
		)
		(pad "6" smd roundrect
			(at -0.202 1.175 180)
			(size 0.22 0.55)
			(layers "F.Cu" "F.Mask" "F.Paste")
			(roundrect_rratio 0.25)
			(net 671 "unconnected-(U40-CLK_{FB}-Pad6)")
			(pinfunction "CLK_{FB}")
			(pintype "output+no_connect")
		)
		(pad "7" smd roundrect
			(at 0.2 1.175 180)
			(size 0.22 0.55)
			(layers "F.Cu" "F.Mask" "F.Paste")
			(roundrect_rratio 0.25)
			(net 1 "GND")
			(pinfunction "GND")
			(pintype "power_in")
		)
		(pad "8" smd roundrect
			(at 0.598 1.175 180)
			(size 0.22 0.55)
			(layers "F.Cu" "F.Mask" "F.Paste")
			(roundrect_rratio 0.25)
			(net 609 "/HDMI + SD Card/SD_CLK")
			(pinfunction "CLK_{B}")
			(pintype "output")
		)
		(pad "9" smd roundrect
			(at 0.623 0.598 270)
			(size 0.22 0.9)
			(layers "F.Cu" "F.Mask" "F.Paste")
			(roundrect_rratio 0.25)
			(net 612 "/HDMI + SD Card/SD_DAT1")
			(pinfunction "DAT1_{B}")
			(pintype "bidirectional")
		)
		(pad "10" smd roundrect
			(at 0.623 0.2 270)
			(size 0.22 0.9)
			(layers "F.Cu" "F.Mask" "F.Paste")
			(roundrect_rratio 0.25)
			(net 611 "/HDMI + SD Card/SD_DAT0")
			(pinfunction "DAT0_{B}")
			(pintype "bidirectional")
		)
		(pad "11" smd roundrect
			(at 0.623 -0.202 270)
			(size 0.22 0.9)
			(layers "F.Cu" "F.Mask" "F.Paste")
			(roundrect_rratio 0.25)
			(net 607 "/HDMI + SD Card/SD_DAT3")
			(pinfunction "DAT3_{B}")
			(pintype "bidirectional")
		)
		(pad "12" smd roundrect
			(at 0.623 -0.6 270)
			(size 0.22 0.9)
			(layers "F.Cu" "F.Mask" "F.Paste")
			(roundrect_rratio 0.25)
			(net 606 "/HDMI + SD Card/SD_DAT2")
			(pinfunction "DAT2_{B}")
			(pintype "bidirectional")
		)
		(pad "13" smd roundrect
			(at 0.598 -1.176 180)
			(size 0.22 0.55)
			(layers "F.Cu" "F.Mask" "F.Paste")
			(roundrect_rratio 0.25)
			(net 608 "/HDMI + SD Card/SD_CMD")
			(pinfunction "CMD_{B}")
			(pintype "bidirectional")
		)
		(pad "14" smd roundrect
			(at 0.2 -1.176 180)
			(size 0.22 0.55)
			(layers "F.Cu" "F.Mask" "F.Paste")
			(roundrect_rratio 0.25)
			(net 647 "/HDMI + SD Card/VCCB")
			(pinfunction "VCC_{B}")
			(pintype "power_in")
		)
		(pad "15" smd roundrect
			(at -0.202 -1.176 180)
			(size 0.22 0.55)
			(layers "F.Cu" "F.Mask" "F.Paste")
			(roundrect_rratio 0.25)
			(net 797 "+1V8")
			(pinfunction "VCC_{A}")
			(pintype "power_in")
		)
		(pad "16" smd roundrect
			(at -0.6 -1.176 180)
			(size 0.22 0.55)
			(layers "F.Cu" "F.Mask" "F.Paste")
			(roundrect_rratio 0.25)
			(net 637 "/FPGA banks HP/SD.CMD")
			(pinfunction "CMD_{A}")
			(pintype "bidirectional")
		)
	)
	(footprint "antmicro-footprints:C_0805_2012Metric"
		(layer "F.Cu")
		(at 262.9 172.9095 90)
		(descr "Capacitor SMD 0805")
		(tags "capacitor SMD 0805")
		(property "Reference" "C182"
			(at 1.9095 0.6 90)
			(layer "F.SilkS")
			(effects
				(font
					(size 0.7 0.7)
					(thickness 0.15)
				)
				(justify left bottom)
			)
		)
		(property "Value" "C_22u_25V_0805"
			(at -2.055717 1.963152 90)
			(layer "F.Fab")
			(effects
				(font
					(size 0.7 0.7)
					(thickness 0.15)
				)
				(justify left bottom)
			)
		)
		(property "Datasheet" "https://product.samsungsem.com/mlcc/CL21A226MAYNNN.do"
			(at 0 0 90)
			(layer "F.Fab")
			(hide yes)
			(effects
				(font
					(size 1.27 1.27)
					(thickness 0.15)
				)
			)
		)
		(property "MPN" "CL21A226MAYNNNE"
			(at 0 0 90)
			(unlocked yes)
			(layer "F.Fab")
			(hide yes)
			(effects
				(font
					(size 1 1)
					(thickness 0.15)
				)
			)
		)
		(property "Manufacturer" "Samsung Electro-Mechanics"
			(at 0 0 90)
			(unlocked yes)
			(layer "F.Fab")
			(hide yes)
			(effects
				(font
					(size 1 1)
					(thickness 0.15)
				)
			)
		)
		(property "License" "Apache-2.0"
			(at 0 0 90)
			(unlocked yes)
			(layer "F.Fab")
			(hide yes)
			(effects
				(font
					(size 1 1)
					(thickness 0.15)
				)
			)
		)
		(property "Author" "Antmicro"
			(at 0 0 90)
			(unlocked yes)
			(layer "F.Fab")
			(hide yes)
			(effects
				(font
					(size 1 1)
					(thickness 0.15)
				)
			)
		)
		(property "Val" "22u"
			(at 0 0 90)
			(unlocked yes)
			(layer "F.Fab")
			(hide yes)
			(effects
				(font
					(size 1 1)
					(thickness 0.15)
				)
			)
		)
		(property "Voltage" "25V"
			(at 0 0 90)
			(unlocked yes)
			(layer "F.Fab")
			(hide yes)
			(effects
				(font
					(size 1 1)
					(thickness 0.15)
				)
			)
		)
		(property "Dielectric" "X5R"
			(at 0 0 90)
			(unlocked yes)
			(layer "F.Fab")
			(hide yes)
			(effects
				(font
					(size 1 1)
					(thickness 0.15)
				)
			)
		)
		(property "Public" "False"
			(at 0 0 90)
			(unlocked yes)
			(layer "F.Fab")
			(hide yes)
			(effects
				(font
					(size 1 1)
					(thickness 0.15)
				)
			)
		)
		(sheetname "/Supply/DC-DC AUX, MGT/")
		(sheetfile "dc-dc-aux-mgt.kicad_sch")
		(attr smd)
		(fp_line
			(start -0.3 -0.7)
			(end 0.3 -0.7)
			(stroke
				(width 0.15)
				(type solid)
			)
			(layer "F.SilkS")
		)
		(fp_line
			(start -0.3 0.7)
			(end 0.3 0.7)
			(stroke
				(width 0.15)
				(type solid)
			)
			(layer "F.SilkS")
		)
		(fp_rect
			(start 1.95 -0.9)
			(end -1.95 0.9)
			(stroke
				(width 0.05)
				(type default)
			)
			(fill no)
			(layer "F.CrtYd")
		)
		(fp_rect
			(start -0.95 -0.675)
			(end 0.95 0.675)
			(stroke
				(width 0.15)
				(type solid)
			)
			(fill no)
			(layer "F.Fab")
		)
		(fp_text user "Author: Antmicro"
			(at -1.9 5.947 90)
			(layer "F.Fab")
			(effects
				(font
					(size 0.7 0.7)
					(thickness 0.15)
				)
				(justify left bottom)
			)
		)
		(fp_text user "License: Apache-2.0"
			(at -1.9 4.947 90)
			(layer "F.Fab")
			(effects
				(font
					(size 0.7 0.7)
					(thickness 0.15)
				)
				(justify left bottom)
			)
		)
		(fp_text user "${REFERENCE}"
			(at -1.9 3.947 90)
			(layer "F.Fab")
			(effects
				(font
					(size 0.7 0.7)
					(thickness 0.15)
				)
				(justify left bottom)
			)
		)
		(pad "1" smd roundrect
			(at -1.1 0 90)
			(size 1.2 1.3)
			(layers "F.Cu" "F.Mask" "F.Paste")
			(roundrect_rratio 0.25)
			(net 1 "GND")
			(pintype "passive")
		)
		(pad "2" smd roundrect
			(at 1.1 0 90)
			(size 1.2 1.3)
			(layers "F.Cu" "F.Mask" "F.Paste")
			(roundrect_rratio 0.25)
			(net 35 "VDC")
			(pintype "passive")
		)
	)
	(footprint "antmicro-footprints:C_0402_1005Metric"
		(layer "F.Cu")
		(at 109.349499 148.564 -90)
		(descr "Capacitor SMD 0402")
		(tags "capacitor SMD 0402")
		(property "Reference" "C133"
			(at 1.011 -0.500501 90)
			(layer "F.SilkS")
			(effects
				(font
					(size 0.7 0.7)
					(thickness 0.15)
				)
				(justify right bottom)
			)
		)
		(property "Value" "C_100n_0402"
			(at -1.022927 2.155213 90)
			(layer "F.Fab")
			(effects
				(font
					(size 0.7 0.7)
					(thickness 0.15)
				)
				(justify right bottom)
			)
		)
		(property "Datasheet" "https://www.murata.com/products/productdetail?partno=GRM155R61H104KE14%23"
			(at 0 0 270)
			(layer "F.Fab")
			(hide yes)
			(effects
				(font
					(size 1.27 1.27)
					(thickness 0.15)
				)
			)
		)
		(property "Manufacturer" "Murata"
			(at 0 0 270)
			(unlocked yes)
			(layer "F.Fab")
			(hide yes)
			(effects
				(font
					(size 1 1)
					(thickness 0.15)
				)
			)
		)
		(property "MPN" "GRM155R61H104KE14D"
			(at 0 0 270)
			(unlocked yes)
			(layer "F.Fab")
			(hide yes)
			(effects
				(font
					(size 1 1)
					(thickness 0.15)
				)
			)
		)
		(property "Val" "100n"
			(at 0 0 270)
			(unlocked yes)
			(layer "F.Fab")
			(hide yes)
			(effects
				(font
					(size 1 1)
					(thickness 0.15)
				)
			)
		)
		(property "License" "Apache-2.0"
			(at 0 0 270)
			(unlocked yes)
			(layer "F.Fab")
			(hide yes)
			(effects
				(font
					(size 1 1)
					(thickness 0.15)
				)
			)
		)
		(property "Author" "Antmicro"
			(at 0 0 270)
			(unlocked yes)
			(layer "F.Fab")
			(hide yes)
			(effects
				(font
					(size 1 1)
					(thickness 0.15)
				)
			)
		)
		(property "Voltage" "50V"
			(at 0 0 270)
			(unlocked yes)
			(layer "F.Fab")
			(hide yes)
			(effects
				(font
					(size 1 1)
					(thickness 0.15)
				)
			)
		)
		(property "Dielectric" "X5R"
			(at 0 0 270)
			(unlocked yes)
			(layer "F.Fab")
			(hide yes)
			(effects
				(font
					(size 1 1)
					(thickness 0.15)
				)
			)
		)
		(sheetname "/Debug FTDI + VNA/")
		(sheetfile "debug-ftdi.kicad_sch")
		(attr smd)
		(fp_rect
			(start -0.925 -0.47)
			(end 0.925 0.47)
			(stroke
				(width 0.05)
				(type default)
			)
			(fill no)
			(layer "F.CrtYd")
		)
		(fp_line
			(start -0.494 0.248)
			(end -0.494 -0.25)
			(stroke
				(width 0.15)
				(type solid)
			)
			(layer "F.Fab")
		)
		(fp_line
			(start 0.504 0.248)
			(end -0.494 0.248)
			(stroke
				(width 0.15)
				(type solid)
			)
			(layer "F.Fab")
		)
		(fp_line
			(start -0.494 -0.25)
			(end 0.504 -0.25)
			(stroke
				(width 0.15)
				(type solid)
			)
			(layer "F.Fab")
		)
		(fp_line
			(start 0.504 -0.25)
			(end 0.504 0.248)
			(stroke
				(width 0.15)
				(type solid)
			)
			(layer "F.Fab")
		)
		(fp_text user "Author: Antmicro"
			(at -0.939 3.399 270)
			(layer "F.Fab")
			(effects
				(font
					(size 0.7 0.7)
					(thickness 0.15)
				)
				(justify left bottom)
			)
		)
		(fp_text user "${REFERENCE}"
			(at -0.939 4.599 270)
			(layer "F.Fab")
			(effects
				(font
					(size 0.7 0.7)
					(thickness 0.15)
				)
				(justify left bottom)
			)
		)
		(fp_text user "License: Apache-2.0"
			(at -0.939 5.799 270)
			(layer "F.Fab")
			(effects
				(font
					(size 0.7 0.7)
					(thickness 0.15)
				)
				(justify left bottom)
			)
		)
		(pad "1" smd roundrect
			(at -0.48 0 270)
			(size 0.59 0.64)
			(layers "F.Cu" "F.Mask" "F.Paste")
			(roundrect_rratio 0.25)
			(net 321 "Net-(C133-Pad1)")
			(pintype "passive")
		)
		(pad "2" smd roundrect
			(at 0.48 0 270)
			(size 0.59 0.64)
			(layers "F.Cu" "F.Mask" "F.Paste")
			(roundrect_rratio 0.25)
			(net 1 "GND")
			(pintype "passive")
		)
	)
)
